(kicad_pcb
	(version 20221018)
	(generator pcbnew)
	(general
    (thickness 1.7403)
  )
	(paper "A4")
	(title_block
    (title "Data Center RDIMM DDR4 Tester")
    (date "2024-09-30")
    (rev "1.2.4")
		(comment 9 "footprints 581-589 of 690")
	)
	(layers
    (0 "F.Cu" signal)
    (1 "In1.Cu" power)
    (2 "In2.Cu" signal)
    (3 "In3.Cu" power)
    (4 "In4.Cu" power)
    (5 "In5.Cu" signal)
    (6 "In6.Cu" power)
    (7 "In7.Cu" signal)
    (8 "In8.Cu" power)
    (9 "In9.Cu" signal)
    (10 "In10.Cu" power)
    (31 "B.Cu" signal)
    (32 "B.Adhes" user "B.Adhesive")
    (33 "F.Adhes" user "F.Adhesive")
    (34 "B.Paste" user)
    (35 "F.Paste" user)
    (36 "B.SilkS" user "B.Silkscreen")
    (37 "F.SilkS" user "F.Silkscreen")
    (38 "B.Mask" user)
    (39 "F.Mask" user)
    (40 "Dwgs.User" user "User.Drawings")
    (41 "Cmts.User" user "User.Comments")
    (42 "Eco1.User" user "User.Eco1")
    (43 "Eco2.User" user "User.Eco2")
    (44 "Edge.Cuts" user)
    (45 "Margin" user)
    (46 "B.CrtYd" user "B.Courtyard")
    (47 "F.CrtYd" user "F.Courtyard")
    (48 "B.Fab" user)
    (49 "F.Fab" user)
  )
	(footprint "data-center-rdimm-ddr4-tester-footprints:SC70-3" (layer "B.Cu")
    (at 238.9 80.4)
    (property "Author" "Antmicro")
    (property "License" "Apache-2.0")
    (property "MPN" "BSS138PW")
    (property "Manufacturer" "Nexperia")
    (property "Sheetfile" "interfaces.kicad_sch")
    (property "Sheetname" "Interfaces")
    (property "ki_description" "60 V, 320 mA N-channel enhancement mode Trench MOSFET, SC-70-3 aka SOT-323 package")
    (property "ki_keywords" "n-channel enhancement mosfet sc70 sc-70 sot-323 sot323")
    (attr smd)
    (fp_text reference "Q9" (at -1.35 0.41 180) (layer "B.SilkS")
        (effects (font (size 0.7 0.7) (thickness 0.15)) (justify left bottom mirror))
    )
    (fp_text value "BSS138PW" (at 0 -2.3 180) (layer "B.Fab") hide
        (effects (font (size 0.7 0.7) (thickness 0.15)) (justify left bottom mirror))
    )
    (fp_text user "License: Apache-2.0" (at -1.45 -6.782 180) (layer "B.Fab") hide
        (effects (font (size 0.7 0.7) (thickness 0.15)) (justify left bottom mirror))
    )
    (fp_text user "Author: Antmicro" (at -1.45 -5.782 180) (layer "B.Fab") hide
        (effects (font (size 0.7 0.7) (thickness 0.15)) (justify left bottom mirror))
    )
    (fp_text user "${REFERENCE}" (at -1.45 -4.783 180) (layer "B.Fab") hide
        (effects (font (size 0.7 0.7) (thickness 0.15)) (justify left bottom mirror))
    )
    (fp_line (start -0.3 -1) (end 0.627 -1.001)
      (stroke (width 0.15) (type solid)) (layer "B.SilkS"))
    (fp_line (start -0.3 1) (end 0.627 0.999)
      (stroke (width 0.15) (type solid)) (layer "B.SilkS"))
    (fp_line (start 0.627 -0.6) (end 0.627 -1.001)
      (stroke (width 0.15) (type solid)) (layer "B.SilkS"))
    (fp_line (start 0.627 0.6) (end 0.627 0.999)
      (stroke (width 0.15) (type solid)) (layer "B.SilkS"))
    (fp_rect (start 1.4 -1.3) (end -1.4 1.3)
      (stroke (width 0.05) (type solid)) (fill none) (layer "B.CrtYd"))
    (fp_rect (start -0.623 0.999) (end 0.627 -1.001)
      (stroke (width 0.15) (type solid)) (fill none) (layer "B.Fab"))
    (pad "1" smd rect (at -0.95 0.65 270) (size 0.6 0.8) (layers "B.Cu" "B.Paste" "B.Mask")
      (net 786 "HOT_SWAP_GREEN") (pinfunction "G") (pintype "bidirectional"))
    (pad "2" smd rect (at -0.95 -0.65 270) (size 0.6 0.8) (layers "B.Cu" "B.Paste" "B.Mask")
      (net 9 "GND") (pinfunction "S") (pintype "bidirectional"))
    (pad "3" smd rect (at 0.95 0 270) (size 0.6 0.8) (layers "B.Cu" "B.Paste" "B.Mask")
      (net 581 "Net-(Q9-D)") (pinfunction "D") (pintype "bidirectional"))
  )
	(footprint "data-center-rdimm-ddr4-tester-footprints:R_0603_1608Metric" (layer "B.Cu")
    (at 185.5 128.65 180)
    (descr "Resistor SMD 0603")
    (tags "resistor SMD 0603")
    (property "Author" "Antmicro")
    (property "License" "Apache-2.0")
    (property "MPN" "CR0603-FX-1301ELF")
    (property "Manufacturer" "Bourns")
    (property "Sheetfile" "ethernet.kicad_sch")
    (property "Sheetname" "Ethernet")
    (property "Tolerance" "1%")
    (property "Val" "1k3")
    (property "ki_description" "1k3 resistor in 0603 package with 1% tolerance")
    (attr smd)
    (fp_text reference "R156" (at -3.96 -0.36) (layer "B.SilkS")
        (effects (font (size 0.7 0.7) (thickness 0.15)) (justify left bottom mirror))
    )
    (fp_text value "R_1k3_0603" (at 0 -1.6) (layer "B.Fab") hide
        (effects (font (size 0.7 0.7) (thickness 0.15)) (justify left bottom mirror))
    )
    (fp_text user "License: Apache-2.0" (at -1.25 -5.9) (layer "B.Fab") hide
        (effects (font (size 0.7 0.7) (thickness 0.15)) (justify left bottom mirror))
    )
    (fp_text user "${REFERENCE}" (at -1.25 -3.898) (layer "B.Fab") hide
        (effects (font (size 0.7 0.7) (thickness 0.15)) (justify left bottom mirror))
    )
    (fp_text user "Author: Antmicro" (at -1.25 -4.9) (layer "B.Fab") hide
        (effects (font (size 0.7 0.7) (thickness 0.15)) (justify left bottom mirror))
    )
    (fp_line (start -0.3 -0.3) (end 0.3 -0.3)
      (stroke (width 0.15) (type solid)) (layer "B.SilkS"))
    (fp_line (start -0.3 0.3) (end 0.3 0.3)
      (stroke (width 0.15) (type solid)) (layer "B.SilkS"))
    (fp_rect (start -1.25 0.7) (end 1.25 -0.7)
      (stroke (width 0.05) (type solid)) (fill none) (layer "B.CrtYd"))
    (fp_rect (start -0.8 0.4) (end 0.8 -0.4)
      (stroke (width 0.15) (type solid)) (fill none) (layer "B.Fab"))
    (pad "1" smd roundrect (at -0.7 0 180) (size 0.6 0.8) (layers "B.Cu" "B.Paste" "B.Mask") (roundrect_rratio 0.2)
      (net 381 "/Ethernet/VSS") (pintype "passive"))
    (pad "2" smd roundrect (at 0.7 0 180) (size 0.6 0.8) (layers "B.Cu" "B.Paste" "B.Mask") (roundrect_rratio 0.2)
      (net 612 "/Ethernet/AMPS_CTL") (pintype "passive"))
  )
	(footprint "data-center-rdimm-ddr4-tester-footprints:C_0201" (layer "B.Cu")
    (at 170.02 101.98 -90)
    (descr "Capacitor SMD 0201")
    (tags "capacitor SMD 0201")
    (property "Author" "Antmicro")
    (property "Dielectric" "")
    (property "License" "Apache-2.0")
    (property "MPN" "CC0201KRX6S5BB104")
    (property "Manufacturer" "Yaego")
    (property "Sheetfile" "fpga-power.kicad_sch")
    (property "Sheetname" "FPGA power")
    (property "Val" "100n")
    (property "Voltage" "")
    (property "ki_description" " ")
    (attr smd)
    (fp_text reference "C306" (at -1.42 0.44 90) (layer "B.SilkS")
        (effects (font (size 0.7 0.7) (thickness 0.15)) (justify left bottom mirror))
    )
    (fp_text value "C_100n_0201" (at 0 -1.4 90) (layer "B.Fab") hide
        (effects (font (size 0.7 0.7) (thickness 0.15)) (justify left bottom mirror))
    )
    (fp_text user "${REFERENCE}" (at -0.72 -3.4 90) (layer "B.Fab") hide
        (effects (font (size 0.7 0.7) (thickness 0.15)) (justify left bottom mirror))
    )
    (fp_text user "License: Apache-2.0" (at -0.72 -4.4 90) (layer "B.Fab") hide
        (effects (font (size 0.7 0.7) (thickness 0.15)) (justify left bottom mirror))
    )
    (fp_text user "Author: Antmicro" (at -0.72 -5.4 90) (layer "B.Fab") hide
        (effects (font (size 0.7 0.7) (thickness 0.15)) (justify left bottom mirror))
    )
    (fp_rect (start -0.72 0.38) (end 0.72 -0.38)
      (stroke (width 0.05) (type solid)) (fill none) (layer "B.CrtYd"))
    (fp_rect (start 0.3 -0.15) (end -0.301 0.149)
      (stroke (width 0.15) (type solid)) (fill none) (layer "B.Fab"))
    (pad "" smd roundrect (at -0.349 0.002 270) (size 0.318 0.36) (layers "B.Paste") (roundrect_rratio 0.25))
    (pad "" smd roundrect (at 0.341 0.002 270) (size 0.318 0.36) (layers "B.Paste") (roundrect_rratio 0.25))
    (pad "1" smd roundrect (at -0.321 0.002 270) (size 0.46 0.4) (layers "B.Cu" "B.Mask") (roundrect_rratio 0.25)
      (net 143 "3V3_SYS") (pintype "passive"))
    (pad "2" smd roundrect (at 0.32 0.002 270) (size 0.46 0.4) (layers "B.Cu" "B.Mask") (roundrect_rratio 0.25)
      (net 9 "GND") (pintype "passive"))
  )
	(footprint "data-center-rdimm-ddr4-tester-footprints:C_0402_1005Metric" (layer "B.Cu")
    (at 119.535 91.1175 180)
    (descr "Capacitor SMD 0402")
    (tags "capacitor SMD 0402")
    (property "Author" "Antmicro")
    (property "Dielectric" "X5R")
    (property "License" "Apache-2.0")
    (property "MPN" "GRM155R61H104KE14D")
    (property "Manufacturer" "Murata")
    (property "Sheetfile" "supply.kicad_sch")
    (property "Sheetname" "Supply")
    (property "Val" "100n")
    (property "Voltage" "50V")
    (property "ki_description" " ")
    (attr smd)
    (fp_text reference "C234" (at -1.395 -1.3225) (layer "B.SilkS")
        (effects (font (size 0.7 0.7) (thickness 0.15)) (justify left bottom mirror))
    )
    (fp_text value "C_100n_0402" (at 0 -1.4) (layer "B.Fab") hide
        (effects (font (size 0.7 0.7) (thickness 0.15)) (justify left bottom mirror))
    )
    (fp_text user "License: Apache-2.0" (at -0.932 -5.17) (layer "B.Fab") hide
        (effects (font (size 0.7 0.7) (thickness 0.15)) (justify left bottom mirror))
    )
    (fp_text user "${REFERENCE}" (at -0.932 -3.168) (layer "B.Fab") hide
        (effects (font (size 0.7 0.7) (thickness 0.15)) (justify left bottom mirror))
    )
    (fp_text user "Author: Antmicro" (at -0.932 -4.17) (layer "B.Fab") hide
        (effects (font (size 0.7 0.7) (thickness 0.15)) (justify left bottom mirror))
    )
    (fp_rect (start -0.94 0.47) (end 0.94 -0.47)
      (stroke (width 0.05) (type solid)) (fill none) (layer "B.CrtYd"))
    (fp_rect (start -0.499 0.249) (end 0.499 -0.249)
      (stroke (width 0.15) (type solid)) (fill none) (layer "B.Fab"))
    (pad "1" smd roundrect (at -0.484 0 180) (size 0.59 0.64) (layers "B.Cu" "B.Paste" "B.Mask") (roundrect_rratio 0.25)
      (net 143 "3V3_SYS") (pintype "passive"))
    (pad "2" smd roundrect (at 0.484 0 180) (size 0.59 0.64) (layers "B.Cu" "B.Paste" "B.Mask") (roundrect_rratio 0.25)
      (net 9 "GND") (pintype "passive"))
  )
	(footprint "data-center-rdimm-ddr4-tester-footprints:SOD-123F" (layer "B.Cu")
    (at 180.91 122.95)
    (property "Author" "Antmicro")
    (property "License" "Apache-2.0")
    (property "MPN" "PTVS58VS1UR,115")
    (property "Manufacturer" "Nexperia")
    (property "Sheetfile" "ethernet.kicad_sch")
    (property "Sheetname" "Ethernet")
    (property "ki_description" "400 W Transient Voltage Suppressor")
    (property "ki_keywords" "400 W Transient Voltage Suppressor")
    (attr smd)
    (fp_text reference "D14" (at 8.08 -3.2 180) (layer "B.SilkS")
        (effects (font (size 0.7 0.7) (thickness 0.15)) (justify left bottom mirror))
    )
    (fp_text value "PTVS58VS1UR,115" (at 0 -2.1 180) (layer "B.Fab") hide
        (effects (font (size 0.7 0.7) (thickness 0.15)) (justify left bottom mirror))
    )
    (fp_text user "License: Apache-2.0" (at -2.202 -6.2 180) (layer "B.Fab") hide
        (effects (font (size 0.7 0.7) (thickness 0.15)) (justify left bottom mirror))
    )
    (fp_text user "Author: Antmicro" (at -2.202 -4.998 180) (layer "B.Fab") hide
        (effects (font (size 0.7 0.7) (thickness 0.15)) (justify left bottom mirror))
    )
    (fp_text user "${REFERENCE}" (at -2.202 -3.798 180) (layer "B.Fab") hide
        (effects (font (size 0.7 0.7) (thickness 0.15)) (justify left bottom mirror))
    )
    (fp_line (start -0.7 0.8) (end -0.7 -0.8)
      (stroke (width 0.15) (type solid)) (layer "B.SilkS"))
    (fp_line (start -2.21 -1.1) (end -2.21 1.1)
      (stroke (width 0.05) (type solid)) (layer "B.CrtYd"))
    (fp_line (start 2.2 -1.1) (end -2.21 -1.1)
      (stroke (width 0.05) (type solid)) (layer "B.CrtYd"))
    (fp_line (start 2.2 1.1) (end -2.21 1.1)
      (stroke (width 0.05) (type solid)) (layer "B.CrtYd"))
    (fp_line (start 2.2 1.1) (end 2.2 -1.1)
      (stroke (width 0.05) (type solid)) (layer "B.CrtYd"))
    (fp_line (start -0.8 0.8) (end -0.8 -0.8)
      (stroke (width 0.1) (type solid)) (layer "B.Fab"))
    (fp_rect (start -1.75 0.802) (end 1.749 -0.8)
      (stroke (width 0.1) (type solid)) (fill none) (layer "B.Fab"))
    (pad "A" smd roundrect (at 1.398 0) (size 1.2 1.2) (layers "B.Cu" "B.Paste" "B.Mask") (roundrect_rratio 0.25)
      (net 381 "/Ethernet/VSS") (pinfunction "A") (pintype "passive"))
    (pad "K" smd roundrect (at -1.401 0) (size 1.2 1.2) (layers "B.Cu" "B.Paste" "B.Mask") (roundrect_rratio 0.25)
      (net 360 "/Ethernet/VDD") (pinfunction "C") (pintype "passive"))
  )
	(footprint "data-center-rdimm-ddr4-tester-footprints:C_0201" (layer "B.Cu")
    (at 174.825 81.65 180)
    (descr "Capacitor SMD 0201")
    (tags "capacitor SMD 0201")
    (property "Author" "Antmicro")
    (property "Dielectric" "")
    (property "License" "Apache-2.0")
    (property "MPN" "CC0201KRX6S5BB104")
    (property "Manufacturer" "Yaego")
    (property "Sheetfile" "fpga-power.kicad_sch")
    (property "Sheetname" "FPGA power")
    (property "Val" "100n")
    (property "Voltage" "")
    (property "ki_description" " ")
    (attr smd)
    (fp_text reference "C92" (at 0.505 -0.39) (layer "B.SilkS")
        (effects (font (size 0.7 0.7) (thickness 0.15)) (justify left bottom mirror))
    )
    (fp_text value "C_100n_0201" (at 0 -1.4) (layer "B.Fab") hide
        (effects (font (size 0.7 0.7) (thickness 0.15)) (justify left bottom mirror))
    )
    (fp_text user "${REFERENCE}" (at -0.72 -3.4) (layer "B.Fab") hide
        (effects (font (size 0.7 0.7) (thickness 0.15)) (justify left bottom mirror))
    )
    (fp_text user "License: Apache-2.0" (at -0.72 -4.4) (layer "B.Fab") hide
        (effects (font (size 0.7 0.7) (thickness 0.15)) (justify left bottom mirror))
    )
    (fp_text user "Author: Antmicro" (at -0.72 -5.4) (layer "B.Fab") hide
        (effects (font (size 0.7 0.7) (thickness 0.15)) (justify left bottom mirror))
    )
    (fp_rect (start -0.72 0.38) (end 0.72 -0.38)
      (stroke (width 0.05) (type solid)) (fill none) (layer "B.CrtYd"))
    (fp_rect (start 0.3 -0.15) (end -0.301 0.149)
      (stroke (width 0.15) (type solid)) (fill none) (layer "B.Fab"))
    (pad "" smd roundrect (at -0.349 0.002 180) (size 0.318 0.36) (layers "B.Paste") (roundrect_rratio 0.25))
    (pad "" smd roundrect (at 0.341 0.002 180) (size 0.318 0.36) (layers "B.Paste") (roundrect_rratio 0.25))
    (pad "1" smd roundrect (at -0.321 0.002 180) (size 0.46 0.4) (layers "B.Cu" "B.Mask") (roundrect_rratio 0.25)
      (net 143 "3V3_SYS") (pintype "passive"))
    (pad "2" smd roundrect (at 0.32 0.002 180) (size 0.46 0.4) (layers "B.Cu" "B.Mask") (roundrect_rratio 0.25)
      (net 9 "GND") (pintype "passive"))
  )
	(footprint "data-center-rdimm-ddr4-tester-footprints:SC70-3" (layer "B.Cu")
    (at 238.9 83.1)
    (property "Author" "Antmicro")
    (property "License" "Apache-2.0")
    (property "MPN" "BSS138PW")
    (property "Manufacturer" "Nexperia")
    (property "Sheetfile" "interfaces.kicad_sch")
    (property "Sheetname" "Interfaces")
    (property "ki_description" "60 V, 320 mA N-channel enhancement mode Trench MOSFET, SC-70-3 aka SOT-323 package")
    (property "ki_keywords" "n-channel enhancement mosfet sc70 sc-70 sot-323 sot323")
    (attr smd)
    (fp_text reference "Q1" (at -1.35 0.41 180) (layer "B.SilkS")
        (effects (font (size 0.7 0.7) (thickness 0.15)) (justify left bottom mirror))
    )
    (fp_text value "BSS138PW" (at 0 -2.3 180) (layer "B.Fab") hide
        (effects (font (size 0.7 0.7) (thickness 0.15)) (justify left bottom mirror))
    )
    (fp_text user "${REFERENCE}" (at -1.45 -4.783 180) (layer "B.Fab") hide
        (effects (font (size 0.7 0.7) (thickness 0.15)) (justify left bottom mirror))
    )
    (fp_text user "License: Apache-2.0" (at -1.45 -6.782 180) (layer "B.Fab") hide
        (effects (font (size 0.7 0.7) (thickness 0.15)) (justify left bottom mirror))
    )
    (fp_text user "Author: Antmicro" (at -1.45 -5.782 180) (layer "B.Fab") hide
        (effects (font (size 0.7 0.7) (thickness 0.15)) (justify left bottom mirror))
    )
    (fp_line (start -0.3 -1) (end 0.627 -1.001)
      (stroke (width 0.15) (type solid)) (layer "B.SilkS"))
    (fp_line (start -0.3 1) (end 0.627 0.999)
      (stroke (width 0.15) (type solid)) (layer "B.SilkS"))
    (fp_line (start 0.627 -0.6) (end 0.627 -1.001)
      (stroke (width 0.15) (type solid)) (layer "B.SilkS"))
    (fp_line (start 0.627 0.6) (end 0.627 0.999)
      (stroke (width 0.15) (type solid)) (layer "B.SilkS"))
    (fp_rect (start 1.4 -1.3) (end -1.4 1.3)
      (stroke (width 0.05) (type solid)) (fill none) (layer "B.CrtYd"))
    (fp_rect (start -0.623 0.999) (end 0.627 -1.001)
      (stroke (width 0.15) (type solid)) (fill none) (layer "B.Fab"))
    (pad "1" smd rect (at -0.95 0.65 270) (size 0.6 0.8) (layers "B.Cu" "B.Paste" "B.Mask")
      (net 784 "HOT_SWAP_YELLOW") (pinfunction "G") (pintype "bidirectional"))
    (pad "2" smd rect (at -0.95 -0.65 270) (size 0.6 0.8) (layers "B.Cu" "B.Paste" "B.Mask")
      (net 9 "GND") (pinfunction "S") (pintype "bidirectional"))
    (pad "3" smd rect (at 0.95 0 270) (size 0.6 0.8) (layers "B.Cu" "B.Paste" "B.Mask")
      (net 573 "Net-(Q1-D)") (pinfunction "D") (pintype "bidirectional"))
  )
	(footprint "data-center-rdimm-ddr4-tester-footprints:Fiducial_1mm_Mask2mm" (layer "B.Cu")
    (at 113 129.5 180)
    (descr "Circular Fiducial, 1mm bare copper, 3mm soldermask opening")
    (tags "fiducial")
    (property "Author" "Antmicro")
    (property "License" "Apache-2.0")
    (property "MPN" "")
    (property "Manufacturer" "")
    (property "Sheetfile" "data-center-rdimm-ddr4-tester.kicad_sch")
    (property "Sheetname" "")
    (property "exclude_from_bom" "")
    (property "ki_description" "Fiducial Marker for use with single board only")
    (attr exclude_from_pos_files exclude_from_bom)
    (fp_text reference "FID5" (at -1.06 1.37) (layer "B.SilkS")
        (effects (font (size 0.7 0.7) (thickness 0.15)) (justify left bottom mirror))
    )
    (fp_text value "Fiducial_1mm_Mask2mm" (at 0 -2.2) (layer "B.Fab") hide
        (effects (font (size 0.7 0.7) (thickness 0.15)) (justify left bottom mirror))
    )
    (fp_text user "${REFERENCE}" (at -1.25 -4.603) (layer "B.Fab") hide
        (effects (font (size 0.7 0.7) (thickness 0.15)) (justify left bottom mirror))
    )
    (fp_text user "License: Apache-2.0" (at -1.25 -7.003) (layer "B.Fab") hide
        (effects (font (size 0.7 0.7) (thickness 0.15)) (justify left bottom mirror))
    )
    (fp_text user "Author: Antmicro" (at -1.25 -5.803) (layer "B.Fab") hide
        (effects (font (size 0.7 0.7) (thickness 0.15)) (justify left bottom mirror))
    )
    (fp_circle (center 0 0) (end 1.24 0)
      (stroke (width 0.05) (type solid)) (fill none) (layer "B.CrtYd"))
    (fp_circle (center 0 0) (end 0.999 0)
      (stroke (width 0.15) (type solid)) (fill none) (layer "B.Fab"))
    (pad "" smd circle (at 0 0 180) (size 1 1) (layers "B.Cu" "B.Mask")
      (solder_mask_margin 0.5) (clearance 0.5))
  )
	(footprint "data-center-rdimm-ddr4-tester-footprints:R_0402_1005Metric" (layer "B.Cu")
    (at 117.725 95.45 90)
    (descr "Resistor SMD 0402")
    (tags "resistor SMD 0402")
    (property "Author" "Antmicro")
    (property "License" "Apache-2.0")
    (property "MPN" "CR0402-FX-1003GLF")
    (property "Manufacturer" "Bourns")
    (property "Sheetfile" "supply.kicad_sch")
    (property "Sheetname" "Supply")
    (property "Tolerance" "1%")
    (property "Val" "100k")
    (property "ki_description" "100k resistor in 0402 package with 1% tolerance")
    (attr smd)
    (fp_text reference "R214" (at 1.83 -0.545 270) (layer "B.SilkS")
        (effects (font (size 0.7 0.7) (thickness 0.15)) (justify left bottom mirror))
    )
    (fp_text value "R_100k_0402" (at 0 -1.4 270) (layer "B.Fab") hide
        (effects (font (size 0.7 0.7) (thickness 0.15)) (justify left bottom mirror))
    )
    (fp_text user "Author: Antmicro" (at -0.95 -4.169 270) (layer "B.Fab") hide
        (effects (font (size 0.7 0.7) (thickness 0.15)) (justify left bottom mirror))
    )
    (fp_text user "License: Apache-2.0" (at -0.95 -5.169 270) (layer "B.Fab") hide
        (effects (font (size 0.7 0.7) (thickness 0.15)) (justify left bottom mirror))
    )
    (fp_text user "${REFERENCE}" (at -0.95 -3.168 270) (layer "B.Fab") hide
        (effects (font (size 0.7 0.7) (thickness 0.15)) (justify left bottom mirror))
    )
    (fp_rect (start -0.93 0.47) (end 0.93 -0.47)
      (stroke (width 0.05) (type solid)) (fill none) (layer "B.CrtYd"))
    (fp_rect (start -0.5 0.25) (end 0.5 -0.25)
      (stroke (width 0.15) (type solid)) (fill none) (layer "B.Fab"))
    (pad "1" smd roundrect (at -0.485 0 90) (size 0.59 0.64) (layers "B.Cu" "B.Paste" "B.Mask") (roundrect_rratio 0.25)
      (net 9 "GND") (pintype "passive"))
    (pad "2" smd roundrect (at 0.485 0 90) (size 0.59 0.64) (layers "B.Cu" "B.Paste" "B.Mask") (roundrect_rratio 0.25)
      (net 799 "FPGA_SLP_S4") (pintype "passive"))
  )
)
